# S9S_MB_2U (Grand Teton) — schematic netlist excerpt (pin names and nets, part order shuffled) for the footprints in the layout excerpt that follows; sources: Cadence DE-HDL packaged netlist, KiCad conversion of 03242023_DA0F0TMBIJ0_F0T_Motherboard_J_brd_V01_OCP.brd

PC2160  Q_CAP  0.1UF 25V 10% X7R  pkg 0402  page 157 : A = P12V_OCP_SFF ; B = GND
C1036  Q_CAP  22UF 4V 20% X6S  pkg C0402  page 74 : A = PVCCIN_CPU0 ; B = GND
C710  Q_CAP_DIFFBUS  DIFF BUS_0.22UF 6.3V 20% X6S  pkg C0201  page 176 : \1\ = P5E_CPU1_PE0_TX_C_DN<15> ; \2\ = P5E_CPU1_PE0_TX_DN<15>

(kicad_pcb
	(version 20260206)
	(generator "pcbnew")
	(generator_version "10.0")
	(general
		(thickness 1.6)
		(legacy_teardrops no)
	)
	(paper "A4")
	(title_block
		(title "03242023_DA0F0TMBIJ0_F0T_Motherboard_J_brd_V01_OCP.brd")
		(comment 1 "Grand Teton / footprints 3499-3501 of 6105")
	)
	(layers
		(0 "F.Cu" signal "TOP")
		(4 "In1.Cu" signal "GND")
		(6 "In2.Cu" signal "IN1")
		(8 "In3.Cu" signal "GND1")
		(10 "In4.Cu" signal "IN2")
		(12 "In5.Cu" signal "GND2")
		(14 "In6.Cu" signal "IN3")
		(16 "In7.Cu" signal "GND3")
		(18 "In8.Cu" signal "VCC")
		(20 "In9.Cu" signal "VCC1")
		(22 "In10.Cu" signal "GND4")
		(24 "In11.Cu" signal "IN4")
		(26 "In12.Cu" signal "GND5")
		(28 "In13.Cu" signal "IN5")
		(30 "In14.Cu" signal "GND6")
		(32 "In15.Cu" signal "IN6")
		(34 "In16.Cu" signal "GND7")
		(2 "B.Cu" signal "BOTTOM")
		(9 "F.Adhes" user "F.Adhesive")
		(11 "B.Adhes" user "B.Adhesive")
		(13 "F.Paste" user "Package Geometry/Pastemask Top")
		(15 "B.Paste" user "Package Geometry/Pastemask Bottom")
		(5 "F.SilkS" user "Ref Des/Silkscreen Top")
		(7 "B.SilkS" user "Ref Des/Silkscreen Bottom")
		(1 "F.Mask" user "Board Geometry/Soldermask Top")
		(3 "B.Mask" user "Board Geometry/Soldermask Bottom")
		(17 "Dwgs.User" user "User.Drawings")
		(19 "Cmts.User" user "User.Comments")
		(21 "Eco1.User" user "User.Eco1")
		(23 "Eco2.User" user "User.Eco2")
		(25 "Edge.Cuts" user "Board Geometry/Outline")
		(27 "Margin" user)
		(31 "F.CrtYd" user "Package Geometry/Place Bound Top")
		(29 "B.CrtYd" user "Package Geometry/Place Bound Bottom")
		(35 "F.Fab" user "Ref Des/Assembly Top")
		(33 "B.Fab" user "Ref Des/Assembly Bottom")
	)
	(footprint ""
		(layer "F.Cu")
		(at 444.598552 -25.477978)
		(property "Reference" "PC2160"
			(at 0 0 0)
			(layer "F.SilkS")
			(hide yes)
			(effects
				(font
					(size 1.27 1.27)
				)
			)
		)
		(property "Value" ""
			(at 0 0 0)
			(layer "F.Fab")
			(effects
				(font
					(size 1.27 1.27)
				)
			)
		)
		(duplicate_pad_numbers_are_jumpers no)
		(fp_line
			(start -0.7874 -0.4064)
			(end 0.7874 -0.4064)
			(stroke
				(width 0.1524)
				(type default)
			)
			(layer "F.SilkS")
		)
		(fp_line
			(start -0.7874 0.4064)
			(end -0.7874 -0.4064)
			(stroke
				(width 0.1524)
				(type default)
			)
			(layer "F.SilkS")
		)
		(fp_line
			(start 0.7874 -0.4064)
			(end 0.7874 0.4064)
			(stroke
				(width 0.1524)
				(type default)
			)
			(layer "F.SilkS")
		)
		(fp_line
			(start 0.7874 0.4064)
			(end -0.7874 0.4064)
			(stroke
				(width 0.1524)
				(type default)
			)
			(layer "F.SilkS")
		)
		(fp_line
			(start -0.67945 -0.305054)
			(end -0.12065 -0.305054)
			(stroke
				(width 0.1)
				(type default)
			)
			(layer "F.Fab")
		)
		(fp_line
			(start -0.67945 0.3048)
			(end -0.67945 -0.305054)
			(stroke
				(width 0.1)
				(type default)
			)
			(layer "F.Fab")
		)
		(fp_line
			(start -0.12065 -0.305054)
			(end -0.12065 -0.2794)
			(stroke
				(width 0.1)
				(type default)
			)
			(layer "F.Fab")
		)
		(fp_line
			(start -0.12065 -0.2794)
			(end 0.12065 -0.2794)
			(stroke
				(width 0.1)
				(type default)
			)
			(layer "F.Fab")
		)
		(fp_line
			(start -0.12065 0.2794)
			(end -0.12065 0.3048)
			(stroke
				(width 0.1)
				(type default)
			)
			(layer "F.Fab")
		)
		(fp_line
			(start -0.12065 0.3048)
			(end -0.67945 0.3048)
			(stroke
				(width 0.1)
				(type default)
			)
			(layer "F.Fab")
		)
		(fp_line
			(start 0.120396 0.2794)
			(end -0.12065 0.2794)
			(stroke
				(width 0.1)
				(type default)
			)
			(layer "F.Fab")
		)
		(fp_line
			(start 0.120396 0.3048)
			(end 0.120396 0.2794)
			(stroke
				(width 0.1)
				(type default)
			)
			(layer "F.Fab")
		)
		(fp_line
			(start 0.12065 -0.3048)
			(end 0.67945 -0.3048)
			(stroke
				(width 0.1)
				(type default)
			)
			(layer "F.Fab")
		)
		(fp_line
			(start 0.12065 -0.2794)
			(end 0.12065 -0.3048)
			(stroke
				(width 0.1)
				(type default)
			)
			(layer "F.Fab")
		)
		(fp_line
			(start 0.67945 -0.3048)
			(end 0.67945 0.3048)
			(stroke
				(width 0.1)
				(type default)
			)
			(layer "F.Fab")
		)
		(fp_line
			(start 0.67945 0.3048)
			(end 0.120396 0.3048)
			(stroke
				(width 0.1)
				(type default)
			)
			(layer "F.Fab")
		)
		(pad "1" smd circle
			(at -0.40005 0)
			(size 0 0)
			(layers "F.Cu" "F.Mask" "F.Paste")
			(net "P12V_OCP_SFF")
		)
		(pad "2" smd circle
			(at 0.40005 0)
			(size 0 0)
			(layers "F.Cu" "F.Mask" "F.Paste")
			(net "GND")
		)
	)
	(footprint ""
		(layer "F.Cu")
		(at 47.954438 -402.371052 -90)
		(property "Reference" "C710"
			(at 0 0 270)
			(layer "F.SilkS")
			(hide yes)
			(effects
				(font
					(size 1.27 1.27)
				)
			)
		)
		(property "Value" ""
			(at 0 0 270)
			(layer "F.Fab")
			(effects
				(font
					(size 1.27 1.27)
				)
			)
		)
		(duplicate_pad_numbers_are_jumpers no)
		(fp_line
			(start -0.299974 0.150114)
			(end -0.299974 -0.150114)
			(stroke
				(width 0.1)
				(type default)
			)
			(layer "F.Fab")
		)
		(fp_line
			(start 0.299974 0.150114)
			(end -0.299974 0.150114)
			(stroke
				(width 0.1)
				(type default)
			)
			(layer "F.Fab")
		)
		(fp_line
			(start -0.299974 -0.150114)
			(end 0.299974 -0.150114)
			(stroke
				(width 0.1)
				(type default)
			)
			(layer "F.Fab")
		)
		(fp_line
			(start 0.299974 -0.150114)
			(end 0.299974 0.150114)
			(stroke
				(width 0.1)
				(type default)
			)
			(layer "F.Fab")
		)
		(pad "1" smd rect
			(at -0.2667 0 270)
			(size 0.3048 0.381)
			(layers "F.Cu" "F.Mask" "F.Paste")
			(net "P5E_CPU1_PE0_TX_C_DN<15>")
		)
		(pad "2" smd rect
			(at 0.2667 0 270)
			(size 0.3048 0.381)
			(layers "F.Cu" "F.Mask" "F.Paste")
			(net "P5E_CPU1_PE0_TX_DN<15>")
		)
	)
	(footprint ""
		(layer "F.Cu")
		(at 365.46663 -251.375418 90)
		(property "Reference" "C1036"
			(at 0 0 90)
			(layer "F.SilkS")
			(hide yes)
			(effects
				(font
					(size 1.27 1.27)
				)
			)
		)
		(property "Value" ""
			(at 0 0 90)
			(layer "F.Fab")
			(effects
				(font
					(size 1.27 1.27)
				)
			)
		)
		(duplicate_pad_numbers_are_jumpers no)
		(fp_line
			(start 0.7874 -0.4064)
			(end 0.7874 0.4064)
			(stroke
				(width 0.1524)
				(type default)
			)
			(layer "F.SilkS")
		)
		(fp_line
			(start -0.7874 -0.4064)
			(end 0.7874 -0.4064)
			(stroke
				(width 0.1524)
				(type default)
			)
			(layer "F.SilkS")
		)
		(fp_line
			(start 0.7874 0.4064)
			(end -0.7874 0.4064)
			(stroke
				(width 0.1524)
				(type default)
			)
			(layer "F.SilkS")
		)
		(fp_line
			(start -0.7874 0.4064)
			(end -0.7874 -0.4064)
			(stroke
				(width 0.1524)
				(type default)
			)
			(layer "F.SilkS")
		)
		(fp_line
			(start -0.12065 -0.305054)
			(end -0.12065 -0.2794)
			(stroke
				(width 0.1)
				(type default)
			)
			(layer "F.Fab")
		)
		(fp_line
			(start -0.67945 -0.305054)
			(end -0.12065 -0.305054)
			(stroke
				(width 0.1)
				(type default)
			)
			(layer "F.Fab")
		)
		(fp_line
			(start 0.67945 -0.3048)
			(end 0.67945 0.3048)
			(stroke
				(width 0.1)
				(type default)
			)
			(layer "F.Fab")
		)
		(fp_line
			(start 0.12065 -0.3048)
			(end 0.67945 -0.3048)
			(stroke
				(width 0.1)
				(type default)
			)
			(layer "F.Fab")
		)
		(fp_line
			(start 0.12065 -0.2794)
			(end 0.12065 -0.3048)
			(stroke
				(width 0.1)
				(type default)
			)
			(layer "F.Fab")
		)
		(fp_line
			(start -0.12065 -0.2794)
			(end 0.12065 -0.2794)
			(stroke
				(width 0.1)
				(type default)
			)
			(layer "F.Fab")
		)
		(fp_line
			(start 0.120396 0.2794)
			(end -0.12065 0.2794)
			(stroke
				(width 0.1)
				(type default)
			)
			(layer "F.Fab")
		)
		(fp_line
			(start -0.12065 0.2794)
			(end -0.12065 0.3048)
			(stroke
				(width 0.1)
				(type default)
			)
			(layer "F.Fab")
		)
		(fp_line
			(start 0.67945 0.3048)
			(end 0.120396 0.3048)
			(stroke
				(width 0.1)
				(type default)
			)
			(layer "F.Fab")
		)
		(fp_line
			(start 0.120396 0.3048)
			(end 0.120396 0.2794)
			(stroke
				(width 0.1)
				(type default)
			)
			(layer "F.Fab")
		)
		(fp_line
			(start -0.12065 0.3048)
			(end -0.67945 0.3048)
			(stroke
				(width 0.1)
				(type default)
			)
			(layer "F.Fab")
		)
		(fp_line
			(start -0.67945 0.3048)
			(end -0.67945 -0.305054)
			(stroke
				(width 0.1)
				(type default)
			)
			(layer "F.Fab")
		)
		(pad "1" smd circle
			(at -0.40005 0 90)
			(size 0 0)
			(layers "F.Cu" "F.Mask" "F.Paste")
			(net "PVCCIN_CPU0")
		)
		(pad "2" smd circle
			(at 0.40005 0 90)
			(size 0 0)
			(layers "F.Cu" "F.Mask" "F.Paste")
			(net "GND")
		)
	)
)
